# S9S_MB_2U (Grand Teton) — schematic netlist excerpt (pin names and nets, part order shuffled) for the footprints in the layout excerpt that follows; sources: Cadence DE-HDL packaged netlist, KiCad conversion of 03242023_DA0F0TMBIJ0_F0T_Motherboard_J_brd_V01_OCP.brd

R3160  Q_RES  1K 1% EMPTY  pkg 0402LF  page 158 : A = P3V3_AUX ; B = HP_OCP_V3_1_RST_R
R2496  Q_RES  1K 1% CHIP  pkg 0402LF  page 115 : A = PWRGD_FAIL_CPU1_EF ; B = PWRGD_FAIL_CPU1_EF_R1

(kicad_pcb
	(version 20260206)
	(generator "pcbnew")
	(generator_version "10.0")
	(general
		(thickness 1.6)
		(legacy_teardrops no)
	)
	(paper "A4")
	(title_block
		(title "03242023_DA0F0TMBIJ0_F0T_Motherboard_J_brd_V01_OCP.brd")
		(comment 1 "Grand Teton / footprints 5236-5237 of 6105")
	)
	(layers
		(0 "F.Cu" signal "TOP")
		(4 "In1.Cu" signal "GND")
		(6 "In2.Cu" signal "IN1")
		(8 "In3.Cu" signal "GND1")
		(10 "In4.Cu" signal "IN2")
		(12 "In5.Cu" signal "GND2")
		(14 "In6.Cu" signal "IN3")
		(16 "In7.Cu" signal "GND3")
		(18 "In8.Cu" signal "VCC")
		(20 "In9.Cu" signal "VCC1")
		(22 "In10.Cu" signal "GND4")
		(24 "In11.Cu" signal "IN4")
		(26 "In12.Cu" signal "GND5")
		(28 "In13.Cu" signal "IN5")
		(30 "In14.Cu" signal "GND6")
		(32 "In15.Cu" signal "IN6")
		(34 "In16.Cu" signal "GND7")
		(2 "B.Cu" signal "BOTTOM")
		(9 "F.Adhes" user "F.Adhesive")
		(11 "B.Adhes" user "B.Adhesive")
		(13 "F.Paste" user "Package Geometry/Pastemask Top")
		(15 "B.Paste" user "Package Geometry/Pastemask Bottom")
		(5 "F.SilkS" user "Ref Des/Silkscreen Top")
		(7 "B.SilkS" user "Ref Des/Silkscreen Bottom")
		(1 "F.Mask" user "Board Geometry/Soldermask Top")
		(3 "B.Mask" user "Board Geometry/Soldermask Bottom")
		(17 "Dwgs.User" user "User.Drawings")
		(19 "Cmts.User" user "User.Comments")
		(21 "Eco1.User" user "User.Eco1")
		(23 "Eco2.User" user "User.Eco2")
		(25 "Edge.Cuts" user "Board Geometry/Outline")
		(27 "Margin" user)
		(31 "F.CrtYd" user "Package Geometry/Place Bound Top")
		(29 "B.CrtYd" user "Package Geometry/Place Bound Bottom")
		(35 "F.Fab" user "Ref Des/Assembly Top")
		(33 "B.Fab" user "Ref Des/Assembly Bottom")
	)
	(footprint ""
		(layer "B.Cu")
		(at 389.636 -32.603948 90)
		(property "Reference" "R3160"
			(at 0 0 90)
			(layer "B.SilkS")
			(hide yes)
			(effects
				(font
					(size 1.27 1.27)
				)
				(justify mirror)
			)
		)
		(property "Value" ""
			(at 0 0 90)
			(layer "B.Fab")
			(effects
				(font
					(size 1.27 1.27)
				)
				(justify mirror)
			)
		)
		(duplicate_pad_numbers_are_jumpers no)
		(fp_line
			(start 0.7874 -0.4064)
			(end -0.7874 -0.4064)
			(stroke
				(width 0.1524)
				(type default)
			)
			(layer "B.SilkS")
		)
		(fp_line
			(start -0.7874 -0.4064)
			(end -0.7874 0.4064)
			(stroke
				(width 0.1524)
				(type default)
			)
			(layer "B.SilkS")
		)
		(fp_line
			(start 0.7874 0.4064)
			(end 0.7874 -0.4064)
			(stroke
				(width 0.1524)
				(type default)
			)
			(layer "B.SilkS")
		)
		(fp_line
			(start -0.7874 0.4064)
			(end 0.7874 0.4064)
			(stroke
				(width 0.1524)
				(type default)
			)
			(layer "B.SilkS")
		)
		(fp_line
			(start 0.67945 -0.305054)
			(end 0.12065 -0.305054)
			(stroke
				(width 0.1)
				(type default)
			)
			(layer "B.Fab")
		)
		(fp_line
			(start 0.12065 -0.305054)
			(end 0.12065 -0.2794)
			(stroke
				(width 0.1)
				(type default)
			)
			(layer "B.Fab")
		)
		(fp_line
			(start -0.12065 -0.3048)
			(end -0.67945 -0.3048)
			(stroke
				(width 0.1)
				(type default)
			)
			(layer "B.Fab")
		)
		(fp_line
			(start -0.67945 -0.3048)
			(end -0.67945 0.3048)
			(stroke
				(width 0.1)
				(type default)
			)
			(layer "B.Fab")
		)
		(fp_line
			(start 0.12065 -0.2794)
			(end -0.12065 -0.2794)
			(stroke
				(width 0.1)
				(type default)
			)
			(layer "B.Fab")
		)
		(fp_line
			(start -0.12065 -0.2794)
			(end -0.12065 -0.3048)
			(stroke
				(width 0.1)
				(type default)
			)
			(layer "B.Fab")
		)
		(fp_line
			(start 0.12065 0.2794)
			(end 0.12065 0.3048)
			(stroke
				(width 0.1)
				(type default)
			)
			(layer "B.Fab")
		)
		(fp_line
			(start -0.120396 0.2794)
			(end 0.12065 0.2794)
			(stroke
				(width 0.1)
				(type default)
			)
			(layer "B.Fab")
		)
		(fp_line
			(start 0.67945 0.3048)
			(end 0.67945 -0.305054)
			(stroke
				(width 0.1)
				(type default)
			)
			(layer "B.Fab")
		)
		(fp_line
			(start 0.12065 0.3048)
			(end 0.67945 0.3048)
			(stroke
				(width 0.1)
				(type default)
			)
			(layer "B.Fab")
		)
		(fp_line
			(start -0.120396 0.3048)
			(end -0.120396 0.2794)
			(stroke
				(width 0.1)
				(type default)
			)
			(layer "B.Fab")
		)
		(fp_line
			(start -0.67945 0.3048)
			(end -0.120396 0.3048)
			(stroke
				(width 0.1)
				(type default)
			)
			(layer "B.Fab")
		)
		(pad "1" smd circle
			(at 0.40005 0 270)
			(size 0 0)
			(layers "B.Cu" "B.Mask" "B.Paste")
			(net "P3V3_AUX")
		)
		(pad "2" smd circle
			(at -0.40005 0 270)
			(size 0 0)
			(layers "B.Cu" "B.Mask" "B.Paste")
			(net "HP_OCP_V3_1_RST_R")
		)
	)
	(footprint ""
		(layer "B.Cu")
		(at 185.555128 -317.40475 180)
		(property "Reference" "R2496"
			(at 0 0 0)
			(layer "B.SilkS")
			(hide yes)
			(effects
				(font
					(size 1.27 1.27)
				)
				(justify mirror)
			)
		)
		(property "Value" ""
			(at 0 0 0)
			(layer "B.Fab")
			(effects
				(font
					(size 1.27 1.27)
				)
				(justify mirror)
			)
		)
		(duplicate_pad_numbers_are_jumpers no)
		(fp_line
			(start 0.7874 0.4064)
			(end 0.7874 -0.4064)
			(stroke
				(width 0.1524)
				(type default)
			)
			(layer "B.SilkS")
		)
		(fp_line
			(start 0.7874 -0.4064)
			(end -0.7874 -0.4064)
			(stroke
				(width 0.1524)
				(type default)
			)
			(layer "B.SilkS")
		)
		(fp_line
			(start -0.7874 0.4064)
			(end 0.7874 0.4064)
			(stroke
				(width 0.1524)
				(type default)
			)
			(layer "B.SilkS")
		)
		(fp_line
			(start -0.7874 -0.4064)
			(end -0.7874 0.4064)
			(stroke
				(width 0.1524)
				(type default)
			)
			(layer "B.SilkS")
		)
		(fp_line
			(start 0.67945 0.3048)
			(end 0.67945 -0.305054)
			(stroke
				(width 0.1)
				(type default)
			)
			(layer "B.Fab")
		)
		(fp_line
			(start 0.67945 -0.305054)
			(end 0.12065 -0.305054)
			(stroke
				(width 0.1)
				(type default)
			)
			(layer "B.Fab")
		)
		(fp_line
			(start 0.12065 0.3048)
			(end 0.67945 0.3048)
			(stroke
				(width 0.1)
				(type default)
			)
			(layer "B.Fab")
		)
		(fp_line
			(start 0.12065 0.2794)
			(end 0.12065 0.3048)
			(stroke
				(width 0.1)
				(type default)
			)
			(layer "B.Fab")
		)
		(fp_line
			(start 0.12065 -0.2794)
			(end -0.12065 -0.2794)
			(stroke
				(width 0.1)
				(type default)
			)
			(layer "B.Fab")
		)
		(fp_line
			(start 0.12065 -0.305054)
			(end 0.12065 -0.2794)
			(stroke
				(width 0.1)
				(type default)
			)
			(layer "B.Fab")
		)
		(fp_line
			(start -0.120396 0.3048)
			(end -0.120396 0.2794)
			(stroke
				(width 0.1)
				(type default)
			)
			(layer "B.Fab")
		)
		(fp_line
			(start -0.120396 0.2794)
			(end 0.12065 0.2794)
			(stroke
				(width 0.1)
				(type default)
			)
			(layer "B.Fab")
		)
		(fp_line
			(start -0.12065 -0.2794)
			(end -0.12065 -0.3048)
			(stroke
				(width 0.1)
				(type default)
			)
			(layer "B.Fab")
		)
		(fp_line
			(start -0.12065 -0.3048)
			(end -0.67945 -0.3048)
			(stroke
				(width 0.1)
				(type default)
			)
			(layer "B.Fab")
		)
		(fp_line
			(start -0.67945 0.3048)
			(end -0.120396 0.3048)
			(stroke
				(width 0.1)
				(type default)
			)
			(layer "B.Fab")
		)
		(fp_line
			(start -0.67945 -0.3048)
			(end -0.67945 0.3048)
			(stroke
				(width 0.1)
				(type default)
			)
			(layer "B.Fab")
		)
		(pad "1" smd circle
			(at 0.40005 0)
			(size 0 0)
			(layers "B.Cu" "B.Mask" "B.Paste")
			(net "PWRGD_FAIL_CPU1_EF")
		)
		(pad "2" smd circle
			(at -0.40005 0)
			(size 0 0)
			(layers "B.Cu" "B.Mask" "B.Paste")
			(net "PWRGD_FAIL_CPU1_EF_R1")
		)
	)
)
